# S9S_MB_2U (Grand Teton) — schematic netlist excerpt (pin names and nets, part order shuffled) for the footprints in the layout excerpt that follows; sources: Cadence DE-HDL packaged netlist, KiCad conversion of 03242023_DA0F0TMBIJ0_F0T_Motherboard_J_brd_V01_OCP.brd

R677  Q_RES  33.2 1% CHIP  pkg 0402LF  page 230 : A = I3C_SPD_DDREFGH_CPU1_LVC1_R_SDA ; B = I3C_SPD_DDREFGH_CPU1_LVC1_SDA
R3469  Q_RES  49.9 1% CHIP  pkg 0402LF  page 149 : A = RST_PERST_0_SWB_BUF_R_N ; B = RST_PERST_0_SWB_BUF_N
PC381  Q_CAP  22UF 4V 20% X6S  pkg C0805  page 297 : A = PVCCD_HV_CPU1 ; B = GND

(kicad_pcb
	(version 20260206)
	(generator "pcbnew")
	(generator_version "10.0")
	(general
		(thickness 1.6)
		(legacy_teardrops no)
	)
	(paper "A4")
	(title_block
		(title "03242023_DA0F0TMBIJ0_F0T_Motherboard_J_brd_V01_OCP.brd")
		(comment 1 "Grand Teton / footprints 74-76 of 6105")
	)
	(layers
		(0 "F.Cu" signal "TOP")
		(4 "In1.Cu" signal "GND")
		(6 "In2.Cu" signal "IN1")
		(8 "In3.Cu" signal "GND1")
		(10 "In4.Cu" signal "IN2")
		(12 "In5.Cu" signal "GND2")
		(14 "In6.Cu" signal "IN3")
		(16 "In7.Cu" signal "GND3")
		(18 "In8.Cu" signal "VCC")
		(20 "In9.Cu" signal "VCC1")
		(22 "In10.Cu" signal "GND4")
		(24 "In11.Cu" signal "IN4")
		(26 "In12.Cu" signal "GND5")
		(28 "In13.Cu" signal "IN5")
		(30 "In14.Cu" signal "GND6")
		(32 "In15.Cu" signal "IN6")
		(34 "In16.Cu" signal "GND7")
		(2 "B.Cu" signal "BOTTOM")
		(9 "F.Adhes" user "F.Adhesive")
		(11 "B.Adhes" user "B.Adhesive")
		(13 "F.Paste" user "Package Geometry/Pastemask Top")
		(15 "B.Paste" user "Package Geometry/Pastemask Bottom")
		(5 "F.SilkS" user "Ref Des/Silkscreen Top")
		(7 "B.SilkS" user "Ref Des/Silkscreen Bottom")
		(1 "F.Mask" user "Board Geometry/Soldermask Top")
		(3 "B.Mask" user "Board Geometry/Soldermask Bottom")
		(17 "Dwgs.User" user "User.Drawings")
		(19 "Cmts.User" user "User.Comments")
		(21 "Eco1.User" user "User.Eco1")
		(23 "Eco2.User" user "User.Eco2")
		(25 "Edge.Cuts" user "Board Geometry/Outline")
		(27 "Margin" user)
		(31 "F.CrtYd" user "Package Geometry/Place Bound Top")
		(29 "B.CrtYd" user "Package Geometry/Place Bound Bottom")
		(35 "F.Fab" user "Ref Des/Assembly Top")
		(33 "B.Fab" user "Ref Des/Assembly Bottom")
	)
	(footprint ""
		(layer "F.Cu")
		(at 80.31861 -152.381204)
		(property "Reference" "R677"
			(at 0 0 0)
			(layer "F.SilkS")
			(hide yes)
			(effects
				(font
					(size 1.27 1.27)
				)
			)
		)
		(property "Value" ""
			(at 0 0 0)
			(layer "F.Fab")
			(effects
				(font
					(size 1.27 1.27)
				)
			)
		)
		(duplicate_pad_numbers_are_jumpers no)
		(fp_line
			(start -0.7874 -0.4064)
			(end 0.7874 -0.4064)
			(stroke
				(width 0.1524)
				(type default)
			)
			(layer "F.SilkS")
		)
		(fp_line
			(start -0.7874 0.4064)
			(end -0.7874 -0.4064)
			(stroke
				(width 0.1524)
				(type default)
			)
			(layer "F.SilkS")
		)
		(fp_line
			(start 0.7874 -0.4064)
			(end 0.7874 0.4064)
			(stroke
				(width 0.1524)
				(type default)
			)
			(layer "F.SilkS")
		)
		(fp_line
			(start 0.7874 0.4064)
			(end -0.7874 0.4064)
			(stroke
				(width 0.1524)
				(type default)
			)
			(layer "F.SilkS")
		)
		(fp_line
			(start -0.67945 -0.305054)
			(end -0.12065 -0.305054)
			(stroke
				(width 0.1)
				(type default)
			)
			(layer "F.Fab")
		)
		(fp_line
			(start -0.67945 0.3048)
			(end -0.67945 -0.305054)
			(stroke
				(width 0.1)
				(type default)
			)
			(layer "F.Fab")
		)
		(fp_line
			(start -0.12065 -0.305054)
			(end -0.12065 -0.2794)
			(stroke
				(width 0.1)
				(type default)
			)
			(layer "F.Fab")
		)
		(fp_line
			(start -0.12065 -0.2794)
			(end 0.12065 -0.2794)
			(stroke
				(width 0.1)
				(type default)
			)
			(layer "F.Fab")
		)
		(fp_line
			(start -0.12065 0.2794)
			(end -0.12065 0.3048)
			(stroke
				(width 0.1)
				(type default)
			)
			(layer "F.Fab")
		)
		(fp_line
			(start -0.12065 0.3048)
			(end -0.67945 0.3048)
			(stroke
				(width 0.1)
				(type default)
			)
			(layer "F.Fab")
		)
		(fp_line
			(start 0.120396 0.2794)
			(end -0.12065 0.2794)
			(stroke
				(width 0.1)
				(type default)
			)
			(layer "F.Fab")
		)
		(fp_line
			(start 0.120396 0.3048)
			(end 0.120396 0.2794)
			(stroke
				(width 0.1)
				(type default)
			)
			(layer "F.Fab")
		)
		(fp_line
			(start 0.12065 -0.3048)
			(end 0.67945 -0.3048)
			(stroke
				(width 0.1)
				(type default)
			)
			(layer "F.Fab")
		)
		(fp_line
			(start 0.12065 -0.2794)
			(end 0.12065 -0.3048)
			(stroke
				(width 0.1)
				(type default)
			)
			(layer "F.Fab")
		)
		(fp_line
			(start 0.67945 -0.3048)
			(end 0.67945 0.3048)
			(stroke
				(width 0.1)
				(type default)
			)
			(layer "F.Fab")
		)
		(fp_line
			(start 0.67945 0.3048)
			(end 0.120396 0.3048)
			(stroke
				(width 0.1)
				(type default)
			)
			(layer "F.Fab")
		)
		(pad "1" smd circle
			(at -0.40005 0)
			(size 0 0)
			(layers "F.Cu" "F.Mask" "F.Paste")
			(net "I3C_SPD_DDREFGH_CPU1_LVC1_R_SDA")
		)
		(pad "2" smd circle
			(at 0.40005 0)
			(size 0 0)
			(layers "F.Cu" "F.Mask" "F.Paste")
			(net "I3C_SPD_DDREFGH_CPU1_LVC1_SDA")
		)
	)
	(footprint ""
		(layer "F.Cu")
		(at 31.29788 -426.303948)
		(property "Reference" "R3469"
			(at 0 0 0)
			(layer "F.SilkS")
			(hide yes)
			(effects
				(font
					(size 1.27 1.27)
				)
			)
		)
		(property "Value" ""
			(at 0 0 0)
			(layer "F.Fab")
			(effects
				(font
					(size 1.27 1.27)
				)
			)
		)
		(duplicate_pad_numbers_are_jumpers no)
		(fp_line
			(start -0.7874 -0.4064)
			(end 0.7874 -0.4064)
			(stroke
				(width 0.1524)
				(type default)
			)
			(layer "F.SilkS")
		)
		(fp_line
			(start -0.7874 0.4064)
			(end -0.7874 -0.4064)
			(stroke
				(width 0.1524)
				(type default)
			)
			(layer "F.SilkS")
		)
		(fp_line
			(start 0.7874 -0.4064)
			(end 0.7874 0.4064)
			(stroke
				(width 0.1524)
				(type default)
			)
			(layer "F.SilkS")
		)
		(fp_line
			(start 0.7874 0.4064)
			(end -0.7874 0.4064)
			(stroke
				(width 0.1524)
				(type default)
			)
			(layer "F.SilkS")
		)
		(fp_line
			(start -0.67945 -0.305054)
			(end -0.12065 -0.305054)
			(stroke
				(width 0.1)
				(type default)
			)
			(layer "F.Fab")
		)
		(fp_line
			(start -0.67945 0.3048)
			(end -0.67945 -0.305054)
			(stroke
				(width 0.1)
				(type default)
			)
			(layer "F.Fab")
		)
		(fp_line
			(start -0.12065 -0.305054)
			(end -0.12065 -0.2794)
			(stroke
				(width 0.1)
				(type default)
			)
			(layer "F.Fab")
		)
		(fp_line
			(start -0.12065 -0.2794)
			(end 0.12065 -0.2794)
			(stroke
				(width 0.1)
				(type default)
			)
			(layer "F.Fab")
		)
		(fp_line
			(start -0.12065 0.2794)
			(end -0.12065 0.3048)
			(stroke
				(width 0.1)
				(type default)
			)
			(layer "F.Fab")
		)
		(fp_line
			(start -0.12065 0.3048)
			(end -0.67945 0.3048)
			(stroke
				(width 0.1)
				(type default)
			)
			(layer "F.Fab")
		)
		(fp_line
			(start 0.120396 0.2794)
			(end -0.12065 0.2794)
			(stroke
				(width 0.1)
				(type default)
			)
			(layer "F.Fab")
		)
		(fp_line
			(start 0.120396 0.3048)
			(end 0.120396 0.2794)
			(stroke
				(width 0.1)
				(type default)
			)
			(layer "F.Fab")
		)
		(fp_line
			(start 0.12065 -0.3048)
			(end 0.67945 -0.3048)
			(stroke
				(width 0.1)
				(type default)
			)
			(layer "F.Fab")
		)
		(fp_line
			(start 0.12065 -0.2794)
			(end 0.12065 -0.3048)
			(stroke
				(width 0.1)
				(type default)
			)
			(layer "F.Fab")
		)
		(fp_line
			(start 0.67945 -0.3048)
			(end 0.67945 0.3048)
			(stroke
				(width 0.1)
				(type default)
			)
			(layer "F.Fab")
		)
		(fp_line
			(start 0.67945 0.3048)
			(end 0.120396 0.3048)
			(stroke
				(width 0.1)
				(type default)
			)
			(layer "F.Fab")
		)
		(pad "1" smd circle
			(at -0.40005 0)
			(size 0 0)
			(layers "F.Cu" "F.Mask" "F.Paste")
			(net "RST_PERST_0_SWB_BUF_R_N")
		)
		(pad "2" smd circle
			(at 0.40005 0)
			(size 0 0)
			(layers "F.Cu" "F.Mask" "F.Paste")
			(net "RST_PERST_0_SWB_BUF_N")
		)
	)
	(footprint ""
		(layer "F.Cu")
		(at 62.996572 -169.6085 180)
		(property "Reference" "PC381"
			(at 0 0 180)
			(layer "F.SilkS")
			(hide yes)
			(effects
				(font
					(size 1.27 1.27)
				)
			)
		)
		(property "Value" ""
			(at 0 0 180)
			(layer "F.Fab")
			(effects
				(font
					(size 1.27 1.27)
				)
			)
		)
		(duplicate_pad_numbers_are_jumpers no)
		(fp_line
			(start 1.524 0.762)
			(end -1.524 0.762)
			(stroke
				(width 0.1524)
				(type default)
			)
			(layer "F.SilkS")
		)
		(fp_line
			(start 1.524 -0.762)
			(end 1.524 0.762)
			(stroke
				(width 0.1524)
				(type default)
			)
			(layer "F.SilkS")
		)
		(fp_line
			(start -1.524 0.762)
			(end -1.524 -0.762)
			(stroke
				(width 0.1524)
				(type default)
			)
			(layer "F.SilkS")
		)
		(fp_line
			(start -1.524 -0.762)
			(end 1.524 -0.762)
			(stroke
				(width 0.1524)
				(type default)
			)
			(layer "F.SilkS")
		)
		(fp_line
			(start 1.1049 0.724916)
			(end 1.1049 -0.724916)
			(stroke
				(width 0.1)
				(type default)
			)
			(layer "F.Fab")
		)
		(fp_line
			(start 1.1049 -0.724916)
			(end -1.1049 -0.724916)
			(stroke
				(width 0.1)
				(type default)
			)
			(layer "F.Fab")
		)
		(fp_line
			(start -1.1049 0.724916)
			(end 1.1049 0.724916)
			(stroke
				(width 0.1)
				(type default)
			)
			(layer "F.Fab")
		)
		(fp_line
			(start -1.1049 -0.724916)
			(end -1.1049 0.724916)
			(stroke
				(width 0.1)
				(type default)
			)
			(layer "F.Fab")
		)
		(pad "1" smd rect
			(at -0.889 0)
			(size 1.016 1.27)
			(layers "F.Cu" "F.Mask" "F.Paste")
			(net "PVCCD_HV_CPU1")
		)
		(pad "2" smd rect
			(at 0.889 0)
			(size 1.016 1.27)
			(layers "F.Cu" "F.Mask" "F.Paste")
			(net "GND")
		)
	)
)
